FILE_TYPE = MULTI_PHYS_TABLE;

PART 'AP331AWG7'

{========================================================================================}
:VALUE        | PART_TYPE | MATERIAL | PART_NUMBER    = STANDARD | LIFECYCLE      | PART_NUMBER   | JEDEC_TYPE | DESCRIPTION                       | MANUFTR | MANUF_PN     | RD_CMPLS_LVL | CMPLS_LVL | FROM_PJ     | CLASS | DIP_SMD | DATA                 | EE_CHECK_LIST | FP_ECN | PSL | CREATOR | STATUS | MSD | ESD_CDM | ESD_HBM | ESD_MM | PIN_LENGTH_SHORT_PIN | PIN_LENGTH_LONG_PIN | CREATEDAY  ;
{========================================================================================}
 'AP331AWG-7' | 'SMLF'    | 'IC'     | 'AL000331011'(!) = ''       | ''               | 'AL000331011' |'SOT25'| 'IC OTHER(5P) AP331AWG-7 (SOT25)' | 'DDS'   | 'AP331AWG-7' | 'EP(V1)'     | 'EP(V1)'  | 'T6G-ALLEN' | 'IC'  | ''      | 'DDS_AP331AWG-7.pdf' | ''            | ''     | ''  | ''      | ''     | ''  | ''      | ''      | ''     | '0 MILS'             | '0 MILS'            | '20210812'
 'AP331AWG-7' | 'SMLF'    | 'EMPTY'  | 'AL000331011'(!) = ''       | ''               | 'AL000331011' |'SOT25'| 'IC OTHER(5P) AP331AWG-7 (SOT25)' | 'DDS'   | 'AP331AWG-7' | 'EP(V1)'     | 'EP(V1)'  | 'T6G-ALLEN' | 'IC'  | ''      | 'DDS_AP331AWG-7.pdf' | ''            | ''     | ''  | ''      | ''     | ''  | ''      | ''      | ''     | '0 MILS'             | '0 MILS'            | '20210812'

END_PART

END.

